# S9S_MB_2U (Grand Teton) — schematic netlist excerpt (pin names and nets, part order shuffled) for the footprints in the layout excerpt that follows; sources: Cadence DE-HDL packaged netlist, KiCad conversion of 03242023_DA0F0TMBIJ0_F0T_Motherboard_J_brd_V01_OCP.brd

PL31  Q_INDUCTOR4P_14  150NH IND  pkg L_TLM117513Q-151QL_11X7-5XA  page 285
  \1\  = SW_PVCCIN_CPU1_SW1
  \2\  = IND_P1_CPL1
  \3\  = IND_P1_CPL6
  \4\  = PVCCIN_CPU1

R3229  Q_RES  200 1% CHIP  pkg 0402LF  page 159 : A = SMB_OCP_V3_2_3V3AUX_BUF_R_SDA ; B = SMB_OCP_V3_2_3V3AUX_BUF_SDA

(kicad_pcb
	(version 20260206)
	(generator "pcbnew")
	(generator_version "10.0")
	(general
		(thickness 1.6)
		(legacy_teardrops no)
	)
	(paper "A4")
	(title_block
		(title "03242023_DA0F0TMBIJ0_F0T_Motherboard_J_brd_V01_OCP.brd")
		(comment 1 "Grand Teton / footprints 3326-3327 of 6105")
	)
	(layers
		(0 "F.Cu" signal "TOP")
		(4 "In1.Cu" signal "GND")
		(6 "In2.Cu" signal "IN1")
		(8 "In3.Cu" signal "GND1")
		(10 "In4.Cu" signal "IN2")
		(12 "In5.Cu" signal "GND2")
		(14 "In6.Cu" signal "IN3")
		(16 "In7.Cu" signal "GND3")
		(18 "In8.Cu" signal "VCC")
		(20 "In9.Cu" signal "VCC1")
		(22 "In10.Cu" signal "GND4")
		(24 "In11.Cu" signal "IN4")
		(26 "In12.Cu" signal "GND5")
		(28 "In13.Cu" signal "IN5")
		(30 "In14.Cu" signal "GND6")
		(32 "In15.Cu" signal "IN6")
		(34 "In16.Cu" signal "GND7")
		(2 "B.Cu" signal "BOTTOM")
		(9 "F.Adhes" user "F.Adhesive")
		(11 "B.Adhes" user "B.Adhesive")
		(13 "F.Paste" user "Package Geometry/Pastemask Top")
		(15 "B.Paste" user "Package Geometry/Pastemask Bottom")
		(5 "F.SilkS" user "Ref Des/Silkscreen Top")
		(7 "B.SilkS" user "Ref Des/Silkscreen Bottom")
		(1 "F.Mask" user "Board Geometry/Soldermask Top")
		(3 "B.Mask" user "Board Geometry/Soldermask Bottom")
		(17 "Dwgs.User" user "User.Drawings")
		(19 "Cmts.User" user "User.Comments")
		(21 "Eco1.User" user "User.Eco1")
		(23 "Eco2.User" user "User.Eco2")
		(25 "Edge.Cuts" user "Board Geometry/Outline")
		(27 "Margin" user)
		(31 "F.CrtYd" user "Package Geometry/Place Bound Top")
		(29 "B.CrtYd" user "Package Geometry/Place Bound Bottom")
		(35 "F.Fab" user "Ref Des/Assembly Top")
		(33 "B.Fab" user "Ref Des/Assembly Bottom")
	)
	(footprint ""
		(layer "F.Cu")
		(at 96.959674 -324.445376)
		(property "Reference" "PL31"
			(at -5.761228 7.068566 90)
			(unlocked yes)
			(layer "F.SilkS")
			(effects
				(font
					(size 0.7874 0.5842)
					(thickness 0.1524)
				)
				(justify left)
			)
		)
		(property "Value" ""
			(at 0 0 0)
			(layer "F.Fab")
			(effects
				(font
					(size 1.27 1.27)
				)
			)
		)
		(duplicate_pad_numbers_are_jumpers no)
		(fp_line
			(start -3.750056 -5.500116)
			(end -2.393442 -5.500116)
			(stroke
				(width 0.1524)
				(type default)
			)
			(layer "F.SilkS")
		)
		(fp_line
			(start -3.750056 5.500116)
			(end -3.750056 -5.500116)
			(stroke
				(width 0.1524)
				(type default)
			)
			(layer "F.SilkS")
		)
		(fp_line
			(start -2.393442 5.500116)
			(end -3.750056 5.500116)
			(stroke
				(width 0.1524)
				(type default)
			)
			(layer "F.SilkS")
		)
		(fp_line
			(start 2.393442 5.500116)
			(end 3.750056 5.500116)
			(stroke
				(width 0.1524)
				(type default)
			)
			(layer "F.SilkS")
		)
		(fp_line
			(start 3.750056 -5.500116)
			(end 2.393442 -5.500116)
			(stroke
				(width 0.1524)
				(type default)
			)
			(layer "F.SilkS")
		)
		(fp_line
			(start 3.750056 5.500116)
			(end 3.750056 -5.500116)
			(stroke
				(width 0.1524)
				(type default)
			)
			(layer "F.SilkS")
		)
		(fp_poly
			(pts
				(xy -3.34391 -6.96722) (xy -2.984754 -5.889498) (xy -4.062222 -6.248654)
			)
			(stroke
				(width 0)
				(type default)
			)
			(fill yes)
			(layer "F.SilkS")
		)
		(fp_line
			(start -3.750056 -5.500116)
			(end -3.750056 5.500116)
			(stroke
				(width 0.1)
				(type default)
			)
			(layer "F.Fab")
		)
		(fp_line
			(start -3.750056 5.500116)
			(end 3.750056 5.500116)
			(stroke
				(width 0.1)
				(type default)
			)
			(layer "F.Fab")
		)
		(fp_line
			(start 3.750056 -5.500116)
			(end -3.750056 -5.500116)
			(stroke
				(width 0.1)
				(type default)
			)
			(layer "F.Fab")
		)
		(fp_line
			(start 3.750056 5.500116)
			(end 3.750056 -5.500116)
			(stroke
				(width 0.1)
				(type default)
			)
			(layer "F.Fab")
		)
		(fp_poly
			(pts
				(xy -4.9276 -4.757928) (xy -4.9276 -3.741928) (xy -3.9116 -4.249928)
			)
			(stroke
				(width 0)
				(type default)
			)
			(fill yes)
			(layer "F.Fab")
		)
		(pad "1" smd rect
			(at 0 -4.249928 270)
			(size 2.413 4.5212)
			(layers "F.Cu" "F.Mask" "F.Paste")
			(net "SW_PVCCIN_CPU1_SW1")
		)
		(pad "2" smd rect
			(at 0 -1.175004 270)
			(size 1.3716 4.5212)
			(layers "F.Cu" "F.Mask" "F.Paste")
			(net "IND_P1_CPL1")
		)
		(pad "3" smd rect
			(at 0 1.175004 270)
			(size 1.3716 4.5212)
			(layers "F.Cu" "F.Mask" "F.Paste")
			(net "IND_P1_CPL6")
		)
		(pad "4" smd rect
			(at 0 4.249928 270)
			(size 2.413 4.5212)
			(layers "F.Cu" "F.Mask" "F.Paste")
			(net "PVCCIN_CPU1")
		)
	)
	(footprint ""
		(layer "F.Cu")
		(at 95.94088 -32.626808)
		(property "Reference" "R3229"
			(at 0 0 0)
			(layer "F.SilkS")
			(hide yes)
			(effects
				(font
					(size 1.27 1.27)
				)
			)
		)
		(property "Value" ""
			(at 0 0 0)
			(layer "F.Fab")
			(effects
				(font
					(size 1.27 1.27)
				)
			)
		)
		(duplicate_pad_numbers_are_jumpers no)
		(fp_line
			(start -0.7874 -0.4064)
			(end 0.7874 -0.4064)
			(stroke
				(width 0.1524)
				(type default)
			)
			(layer "F.SilkS")
		)
		(fp_line
			(start -0.7874 0.4064)
			(end -0.7874 -0.4064)
			(stroke
				(width 0.1524)
				(type default)
			)
			(layer "F.SilkS")
		)
		(fp_line
			(start 0.7874 -0.4064)
			(end 0.7874 0.4064)
			(stroke
				(width 0.1524)
				(type default)
			)
			(layer "F.SilkS")
		)
		(fp_line
			(start 0.7874 0.4064)
			(end -0.7874 0.4064)
			(stroke
				(width 0.1524)
				(type default)
			)
			(layer "F.SilkS")
		)
		(fp_line
			(start -0.67945 -0.305054)
			(end -0.12065 -0.305054)
			(stroke
				(width 0.1)
				(type default)
			)
			(layer "F.Fab")
		)
		(fp_line
			(start -0.67945 0.3048)
			(end -0.67945 -0.305054)
			(stroke
				(width 0.1)
				(type default)
			)
			(layer "F.Fab")
		)
		(fp_line
			(start -0.12065 -0.305054)
			(end -0.12065 -0.2794)
			(stroke
				(width 0.1)
				(type default)
			)
			(layer "F.Fab")
		)
		(fp_line
			(start -0.12065 -0.2794)
			(end 0.12065 -0.2794)
			(stroke
				(width 0.1)
				(type default)
			)
			(layer "F.Fab")
		)
		(fp_line
			(start -0.12065 0.2794)
			(end -0.12065 0.3048)
			(stroke
				(width 0.1)
				(type default)
			)
			(layer "F.Fab")
		)
		(fp_line
			(start -0.12065 0.3048)
			(end -0.67945 0.3048)
			(stroke
				(width 0.1)
				(type default)
			)
			(layer "F.Fab")
		)
		(fp_line
			(start 0.120396 0.2794)
			(end -0.12065 0.2794)
			(stroke
				(width 0.1)
				(type default)
			)
			(layer "F.Fab")
		)
		(fp_line
			(start 0.120396 0.3048)
			(end 0.120396 0.2794)
			(stroke
				(width 0.1)
				(type default)
			)
			(layer "F.Fab")
		)
		(fp_line
			(start 0.12065 -0.3048)
			(end 0.67945 -0.3048)
			(stroke
				(width 0.1)
				(type default)
			)
			(layer "F.Fab")
		)
		(fp_line
			(start 0.12065 -0.2794)
			(end 0.12065 -0.3048)
			(stroke
				(width 0.1)
				(type default)
			)
			(layer "F.Fab")
		)
		(fp_line
			(start 0.67945 -0.3048)
			(end 0.67945 0.3048)
			(stroke
				(width 0.1)
				(type default)
			)
			(layer "F.Fab")
		)
		(fp_line
			(start 0.67945 0.3048)
			(end 0.120396 0.3048)
			(stroke
				(width 0.1)
				(type default)
			)
			(layer "F.Fab")
		)
		(pad "1" smd circle
			(at -0.40005 0)
			(size 0 0)
			(layers "F.Cu" "F.Mask" "F.Paste")
			(net "SMB_OCP_V3_2_3V3AUX_BUF_R_SDA")
		)
		(pad "2" smd circle
			(at 0.40005 0)
			(size 0 0)
			(layers "F.Cu" "F.Mask" "F.Paste")
			(net "SMB_OCP_V3_2_3V3AUX_BUF_SDA")
		)
	)
)
